# BASEBOARD_FAB2 (Tioga Pass) — schematic netlist excerpt (pin names and nets, part order shuffled) for the footprints in the layout excerpt that follows; sources: Cadence DE-HDL packaged netlist, KiCad conversion of Wiwynn_Tioga_Pass_MB.brd

R25W36  120R2F-GP  1%  pkg RCL_GP  page 151 : \1\ = BMC_M_BA1 ; \2\ = P1V2_AUX_BMC
C9N3  CAP  0.22UF 16V 10% X7R  pkg 0402  page 182 : A = P3E_CPU1_PE3_MP_C_TXN<11> ; B = P3E_CPU1_PE3_MP_TXN<11>
R1U23  RES  2.7K 1% CHIP  pkg 0402  page 164 : A = P3V3_STBY ; B = FM_BOARD_SKU_ID0

(kicad_pcb
	(version 20260206)
	(generator "pcbnew")
	(generator_version "10.0")
	(general
		(thickness 1.6)
		(legacy_teardrops no)
	)
	(paper "A4")
	(title_block
		(title "Wiwynn_Tioga_Pass_MB.brd")
		(comment 1 "Tioga Pass / footprints 3935-3937 of 4770")
	)
	(layers
		(0 "F.Cu" signal "TOP")
		(4 "In1.Cu" signal "L2GND")
		(6 "In2.Cu" signal "L3")
		(8 "In3.Cu" signal "L4GND")
		(10 "In4.Cu" signal "L5")
		(12 "In5.Cu" signal "L6GND")
		(14 "In6.Cu" signal "L7VCC")
		(16 "In7.Cu" signal "L8VCC")
		(18 "In8.Cu" signal "L9GND")
		(20 "In9.Cu" signal "L10")
		(22 "In10.Cu" signal "L11GND")
		(24 "In11.Cu" signal "L12")
		(26 "In12.Cu" signal "L13GND")
		(2 "B.Cu" signal "BOTTOM")
		(9 "F.Adhes" user "F.Adhesive")
		(11 "B.Adhes" user "B.Adhesive")
		(13 "F.Paste" user "Package Geometry/Pastemask Top")
		(15 "B.Paste" user "Package Geometry/Pastemask Bottom")
		(5 "F.SilkS" user "Ref Des/Silkscreen Top")
		(7 "B.SilkS" user "Ref Des/Silkscreen Bottom")
		(1 "F.Mask" user "Board Geometry/Soldermask Top")
		(3 "B.Mask" user "Board Geometry/Soldermask Bottom")
		(17 "Dwgs.User" user "User.Drawings")
		(19 "Cmts.User" user "User.Comments")
		(21 "Eco1.User" user "User.Eco1")
		(23 "Eco2.User" user "User.Eco2")
		(25 "Edge.Cuts" user "Board Geometry/Outline")
		(27 "Margin" user)
		(31 "F.CrtYd" user "Package Geometry/Place Bound Top")
		(29 "B.CrtYd" user "Package Geometry/Place Bound Bottom")
		(35 "F.Fab" user "Ref Des/Assembly Top")
		(33 "B.Fab" user "Ref Des/Assembly Bottom")
	)
	(footprint ""
		(layer "B.Cu")
		(at 13.84046 -107.48518 90)
		(property "Reference" "C9N3"
			(at 0 0 90)
			(layer "B.SilkS")
			(hide yes)
			(effects
				(font
					(size 1.27 1.27)
				)
				(justify mirror)
			)
		)
		(property "Value" ""
			(at 0 0 90)
			(layer "B.Fab")
			(effects
				(font
					(size 1.27 1.27)
				)
				(justify mirror)
			)
		)
		(duplicate_pad_numbers_are_jumpers no)
		(fp_poly
			(pts
				(xy -0.3048 -0.1016) (xy -0.3048 0.9906) (xy 0.3048 0.9906) (xy 0.3048 -0.1016)
			)
			(stroke
				(width 0)
				(type default)
			)
			(fill no)
			(layer "B.CrtYd")
		)
		(fp_line
			(start 0.3048 -0.1016)
			(end 0.3048 0.9906)
			(stroke
				(width 0.1)
				(type default)
			)
			(layer "B.Fab")
		)
		(fp_line
			(start -0.3048 -0.1016)
			(end 0.3048 -0.1016)
			(stroke
				(width 0.1)
				(type default)
			)
			(layer "B.Fab")
		)
		(fp_line
			(start 0.3048 0.9906)
			(end -0.3048 0.9906)
			(stroke
				(width 0.1)
				(type default)
			)
			(layer "B.Fab")
		)
		(fp_line
			(start -0.3048 0.9906)
			(end -0.3048 -0.1016)
			(stroke
				(width 0.1)
				(type default)
			)
			(layer "B.Fab")
		)
		(pad "1" smd rect
			(at 0 0 270)
			(size 0.508 0.508)
			(layers "B.Cu" "B.Mask" "B.Paste")
			(net "P3E_CPU1_PE3_MP_C_TXN<11>")
		)
		(pad "2" smd rect
			(at 0 0.889 270)
			(size 0.508 0.508)
			(layers "B.Cu" "B.Mask" "B.Paste")
			(net "P3E_CPU1_PE3_MP_TXN<11>")
		)
		(zone
			(layer "B.Cu")
			(hatch none 0.5)
			(connect_pads
				(clearance 0)
			)
			(min_thickness 0.25)
			(keepout
				(tracks allowed)
				(vias not_allowed)
				(pads allowed)
				(copperpour not_allowed)
				(footprints allowed)
			)
			(placement
				(enabled no)
				(sheetname "")
			)
			(fill
				(thermal_gap 0.5)
				(thermal_bridge_width 0.5)
				(island_removal_mode 0)
			)
			(polygon
				(pts
					(xy 14.09446 -107.73918) (xy 14.09446 -107.23118) (xy 14.47546 -107.23118) (xy 14.47546 -107.73918)
				)
			)
		)
		(zone
			(layer "B.Cu")
			(hatch none 0.5)
			(connect_pads
				(clearance 0)
			)
			(min_thickness 0.25)
			(keepout
				(tracks not_allowed)
				(vias allowed)
				(pads allowed)
				(copperpour not_allowed)
				(footprints allowed)
			)
			(placement
				(enabled no)
				(sheetname "")
			)
			(fill
				(thermal_gap 0.5)
				(thermal_bridge_width 0.5)
				(island_removal_mode 0)
			)
			(polygon
				(pts
					(xy 14.47546 -107.73918) (xy 14.47546 -107.23118) (xy 14.09446 -107.23118) (xy 14.09446 -107.73918)
				)
			)
		)
	)
	(footprint ""
		(layer "B.Cu")
		(at 430.4792 -22.5298 180)
		(property "Reference" "R1U23"
			(at 0 0 0)
			(layer "B.SilkS")
			(hide yes)
			(effects
				(font
					(size 1.27 1.27)
				)
				(justify mirror)
			)
		)
		(property "Value" ""
			(at 0 0 0)
			(layer "B.Fab")
			(effects
				(font
					(size 1.27 1.27)
				)
				(justify mirror)
			)
		)
		(duplicate_pad_numbers_are_jumpers no)
		(fp_poly
			(pts
				(xy 0.2794 -0.1016) (xy -0.2794 -0.1016) (xy -0.2794 0.9906) (xy 0.2794 0.9906)
			)
			(stroke
				(width 0)
				(type default)
			)
			(fill no)
			(layer "B.CrtYd")
		)
		(fp_line
			(start 0.2794 0.9906)
			(end -0.2794 0.9906)
			(stroke
				(width 0.1)
				(type default)
			)
			(layer "B.Fab")
		)
		(fp_line
			(start 0.2794 -0.1016)
			(end 0.2794 0.9906)
			(stroke
				(width 0.1)
				(type default)
			)
			(layer "B.Fab")
		)
		(fp_line
			(start -0.2794 0.9906)
			(end -0.2794 -0.1016)
			(stroke
				(width 0.1)
				(type default)
			)
			(layer "B.Fab")
		)
		(fp_line
			(start -0.2794 -0.1016)
			(end 0.2794 -0.1016)
			(stroke
				(width 0.1)
				(type default)
			)
			(layer "B.Fab")
		)
		(pad "1" smd rect
			(at 0 0)
			(size 0.508 0.508)
			(layers "B.Cu" "B.Mask" "B.Paste")
			(net "P3V3_STBY")
		)
		(pad "2" smd rect
			(at 0 0.889)
			(size 0.508 0.508)
			(layers "B.Cu" "B.Mask" "B.Paste")
			(net "FM_BOARD_SKU_ID0")
		)
		(zone
			(layer "B.Cu")
			(hatch none 0.5)
			(connect_pads
				(clearance 0)
			)
			(min_thickness 0.25)
			(keepout
				(tracks not_allowed)
				(vias allowed)
				(pads allowed)
				(copperpour not_allowed)
				(footprints allowed)
			)
			(placement
				(enabled no)
				(sheetname "")
			)
			(fill
				(thermal_gap 0.5)
				(thermal_bridge_width 0.5)
				(island_removal_mode 0)
			)
			(polygon
				(pts
					(xy 430.2252 -23.1648) (xy 430.7332 -23.1648) (xy 430.7332 -22.7838) (xy 430.2252 -22.7838)
				)
			)
		)
		(zone
			(layer "B.Cu")
			(hatch none 0.5)
			(connect_pads
				(clearance 0)
			)
			(min_thickness 0.25)
			(keepout
				(tracks allowed)
				(vias not_allowed)
				(pads allowed)
				(copperpour not_allowed)
				(footprints allowed)
			)
			(placement
				(enabled no)
				(sheetname "")
			)
			(fill
				(thermal_gap 0.5)
				(thermal_bridge_width 0.5)
				(island_removal_mode 0)
			)
			(polygon
				(pts
					(xy 430.2252 -22.7838) (xy 430.7332 -22.7838) (xy 430.7332 -23.1648) (xy 430.2252 -23.1648)
				)
			)
		)
	)
	(footprint ""
		(layer "B.Cu")
		(at 438.833006 -43.54195 180)
		(property "Reference" "R25W36"
			(at 0 0 0)
			(layer "B.SilkS")
			(hide yes)
			(effects
				(font
					(size 1.27 1.27)
				)
				(justify mirror)
			)
		)
		(property "Value" "*"
			(at -0.064008 -4.108196 180)
			(unlocked yes)
			(layer "B.Fab")
			(hide yes)
			(effects
				(font
					(size 1.27 1.016)
					(thickness 0.1524)
				)
				(justify mirror)
			)
		)
		(property "Device Type" "120R2F-GP_RCL_GP-120R2F-GP,64.A"
			(at -0.064008 -5.632196 180)
			(unlocked yes)
			(layer "B.Fab")
			(hide yes)
			(effects
				(font
					(size 1.27 1.016)
					(thickness 0.1524)
				)
				(justify mirror)
			)
		)
		(duplicate_pad_numbers_are_jumpers no)
		(fp_line
			(start 0.508 -0.9398)
			(end 0.508 0.9398)
			(stroke
				(width 0.1524)
				(type default)
			)
			(layer "B.SilkS")
		)
		(fp_line
			(start -0.508 -0.9398)
			(end 0.508 -0.9398)
			(stroke
				(width 0.1524)
				(type default)
			)
			(layer "B.SilkS")
		)
		(fp_rect
			(start 0.508 0.9398)
			(end -0.508 -0.9398)
			(stroke
				(width 0)
				(type default)
			)
			(fill no)
			(layer "B.CrtYd")
		)
		(fp_rect
			(start 0.508 0.9398)
			(end -0.508 -0.9398)
			(stroke
				(width 0)
				(type default)
			)
			(fill no)
			(layer "B.Fab")
		)
		(pad "1" smd custom
			(at 0 -0.4445)
			(size 0.1397 0.1397)
			(layers "B.Cu" "B.Mask" "B.Paste")
			(net "BMC_M_BA1")
			(options
				(clearance outline)
				(anchor circle)
			)
			(primitives
				(gr_poly
					(pts
						(arc
							(start -0.1778 0.2794)
							(mid -0.249642 0.249642)
							(end -0.2794 0.1778)
						)
						(arc
							(start -0.2794 -0.1778)
							(mid -0.249642 -0.249642)
							(end -0.1778 -0.2794)
						)
						(arc
							(start 0.1778 -0.2794)
							(mid 0.249642 -0.249642)
							(end 0.2794 -0.1778)
						)
						(arc
							(start 0.2794 0.1778)
							(mid 0.249642 0.249642)
							(end 0.1778 0.2794)
						)
					)
					(width 0)
					(fill yes)
				)
			)
		)
		(pad "2" smd custom
			(at 0 0.4445)
			(size 0.1397 0.1397)
			(layers "B.Cu" "B.Mask" "B.Paste")
			(net "P1V2_AUX_BMC")
			(options
				(clearance outline)
				(anchor circle)
			)
			(primitives
				(gr_poly
					(pts
						(arc
							(start -0.1778 0.2794)
							(mid -0.249642 0.249642)
							(end -0.2794 0.1778)
						)
						(arc
							(start -0.2794 -0.1778)
							(mid -0.249642 -0.249642)
							(end -0.1778 -0.2794)
						)
						(arc
							(start 0.1778 -0.2794)
							(mid 0.249642 -0.249642)
							(end 0.2794 -0.1778)
						)
						(arc
							(start 0.2794 0.1778)
							(mid 0.249642 0.249642)
							(end 0.1778 0.2794)
						)
					)
					(width 0)
					(fill yes)
				)
			)
		)
	)
)
